(kicad_pcb
	(version 20260206)
	(generator "pcbnew")
	(generator_version "10.0")
	(general
		(thickness 1.6)
		(legacy_teardrops no)
	)
	(paper "A4")
	(title_block
		(title "12092022_DA0F0TFB6D0_F0T_FAN_BOARD_MP5048_D_brd_v02_OCP.brd")
		(comment 1 "Grand Teton / footprints 471-476 of 924")
	)
	(layers
		(0 "F.Cu" signal "TOP")
		(4 "In1.Cu" signal "GND")
		(6 "In2.Cu" signal "IN1")
		(8 "In3.Cu" signal "IN2")
		(10 "In4.Cu" signal "GND1")
		(2 "B.Cu" signal "BOTTOM")
		(9 "F.Adhes" user "F.Adhesive")
		(11 "B.Adhes" user "B.Adhesive")
		(13 "F.Paste" user "Package Geometry/Pastemask Top")
		(15 "B.Paste" user "Package Geometry/Pastemask Bottom")
		(5 "F.SilkS" user "Ref Des/Silkscreen Top")
		(7 "B.SilkS" user "Ref Des/Silkscreen Bottom")
		(1 "F.Mask" user "Board Geometry/Soldermask Top")
		(3 "B.Mask" user "Board Geometry/Soldermask Bottom")
		(17 "Dwgs.User" user "User.Drawings")
		(19 "Cmts.User" user "User.Comments")
		(21 "Eco1.User" user "User.Eco1")
		(23 "Eco2.User" user "User.Eco2")
		(25 "Edge.Cuts" user "Board Geometry/Outline")
		(27 "Margin" user)
		(31 "F.CrtYd" user "Package Geometry/Place Bound Top")
		(29 "B.CrtYd" user "Package Geometry/Place Bound Bottom")
		(35 "F.Fab" user "Ref Des/Assembly Top")
		(33 "B.Fab" user "Ref Des/Assembly Bottom")
	)
	(footprint ""
		(layer "F.Cu")
		(at 31.369 -16.891)
		(property "Reference" "C2090"
			(at 0 0 0)
			(layer "F.SilkS")
			(hide yes)
			(effects
				(font
					(size 1.27 1.27)
				)
			)
		)
		(property "Value" ""
			(at 0 0 0)
			(layer "F.Fab")
			(effects
				(font
					(size 1.27 1.27)
				)
			)
		)
		(duplicate_pad_numbers_are_jumpers no)
		(fp_line
			(start -0.7874 -0.4064)
			(end 0.7874 -0.4064)
			(stroke
				(width 0.1524)
				(type default)
			)
			(layer "F.SilkS")
		)
		(fp_line
			(start -0.7874 0.4064)
			(end -0.7874 -0.4064)
			(stroke
				(width 0.1524)
				(type default)
			)
			(layer "F.SilkS")
		)
		(fp_line
			(start 0.7874 -0.4064)
			(end 0.7874 0.4064)
			(stroke
				(width 0.1524)
				(type default)
			)
			(layer "F.SilkS")
		)
		(fp_line
			(start 0.7874 0.4064)
			(end -0.7874 0.4064)
			(stroke
				(width 0.1524)
				(type default)
			)
			(layer "F.SilkS")
		)
		(fp_line
			(start -0.67945 -0.305054)
			(end -0.12065 -0.305054)
			(stroke
				(width 0.1)
				(type default)
			)
			(layer "F.Fab")
		)
		(fp_line
			(start -0.67945 0.3048)
			(end -0.67945 -0.305054)
			(stroke
				(width 0.1)
				(type default)
			)
			(layer "F.Fab")
		)
		(fp_line
			(start -0.12065 -0.305054)
			(end -0.12065 -0.2794)
			(stroke
				(width 0.1)
				(type default)
			)
			(layer "F.Fab")
		)
		(fp_line
			(start -0.12065 -0.2794)
			(end 0.12065 -0.2794)
			(stroke
				(width 0.1)
				(type default)
			)
			(layer "F.Fab")
		)
		(fp_line
			(start -0.12065 0.2794)
			(end -0.12065 0.3048)
			(stroke
				(width 0.1)
				(type default)
			)
			(layer "F.Fab")
		)
		(fp_line
			(start -0.12065 0.3048)
			(end -0.67945 0.3048)
			(stroke
				(width 0.1)
				(type default)
			)
			(layer "F.Fab")
		)
		(fp_line
			(start 0.120396 0.2794)
			(end -0.12065 0.2794)
			(stroke
				(width 0.1)
				(type default)
			)
			(layer "F.Fab")
		)
		(fp_line
			(start 0.120396 0.3048)
			(end 0.120396 0.2794)
			(stroke
				(width 0.1)
				(type default)
			)
			(layer "F.Fab")
		)
		(fp_line
			(start 0.12065 -0.3048)
			(end 0.67945 -0.3048)
			(stroke
				(width 0.1)
				(type default)
			)
			(layer "F.Fab")
		)
		(fp_line
			(start 0.12065 -0.2794)
			(end 0.12065 -0.3048)
			(stroke
				(width 0.1)
				(type default)
			)
			(layer "F.Fab")
		)
		(fp_line
			(start 0.67945 -0.3048)
			(end 0.67945 0.3048)
			(stroke
				(width 0.1)
				(type default)
			)
			(layer "F.Fab")
		)
		(fp_line
			(start 0.67945 0.3048)
			(end 0.120396 0.3048)
			(stroke
				(width 0.1)
				(type default)
			)
			(layer "F.Fab")
		)
		(pad "1" smd circle
			(at -0.40005 0)
			(size 0 0)
			(layers "F.Cu" "F.Mask" "F.Paste")
			(net "P3V3_AUX")
		)
		(pad "2" smd circle
			(at 0.40005 0)
			(size 0 0)
			(layers "F.Cu" "F.Mask" "F.Paste")
			(net "GND")
		)
	)
	(footprint ""
		(layer "F.Cu")
		(at 34.925 -200.8632)
		(property "Reference" "R5528"
			(at 0 0 0)
			(layer "F.SilkS")
			(hide yes)
			(effects
				(font
					(size 1.27 1.27)
				)
			)
		)
		(property "Value" ""
			(at 0 0 0)
			(layer "F.Fab")
			(effects
				(font
					(size 1.27 1.27)
				)
			)
		)
		(duplicate_pad_numbers_are_jumpers no)
		(fp_line
			(start -0.7874 -0.4064)
			(end 0.7874 -0.4064)
			(stroke
				(width 0.1524)
				(type default)
			)
			(layer "F.SilkS")
		)
		(fp_line
			(start -0.7874 0.4064)
			(end -0.7874 -0.4064)
			(stroke
				(width 0.1524)
				(type default)
			)
			(layer "F.SilkS")
		)
		(fp_line
			(start 0.7874 -0.4064)
			(end 0.7874 0.4064)
			(stroke
				(width 0.1524)
				(type default)
			)
			(layer "F.SilkS")
		)
		(fp_line
			(start 0.7874 0.4064)
			(end -0.7874 0.4064)
			(stroke
				(width 0.1524)
				(type default)
			)
			(layer "F.SilkS")
		)
		(fp_line
			(start -0.67945 -0.305054)
			(end -0.12065 -0.305054)
			(stroke
				(width 0.1)
				(type default)
			)
			(layer "F.Fab")
		)
		(fp_line
			(start -0.67945 0.3048)
			(end -0.67945 -0.305054)
			(stroke
				(width 0.1)
				(type default)
			)
			(layer "F.Fab")
		)
		(fp_line
			(start -0.12065 -0.305054)
			(end -0.12065 -0.2794)
			(stroke
				(width 0.1)
				(type default)
			)
			(layer "F.Fab")
		)
		(fp_line
			(start -0.12065 -0.2794)
			(end 0.12065 -0.2794)
			(stroke
				(width 0.1)
				(type default)
			)
			(layer "F.Fab")
		)
		(fp_line
			(start -0.12065 0.2794)
			(end -0.12065 0.3048)
			(stroke
				(width 0.1)
				(type default)
			)
			(layer "F.Fab")
		)
		(fp_line
			(start -0.12065 0.3048)
			(end -0.67945 0.3048)
			(stroke
				(width 0.1)
				(type default)
			)
			(layer "F.Fab")
		)
		(fp_line
			(start 0.120396 0.2794)
			(end -0.12065 0.2794)
			(stroke
				(width 0.1)
				(type default)
			)
			(layer "F.Fab")
		)
		(fp_line
			(start 0.120396 0.3048)
			(end 0.120396 0.2794)
			(stroke
				(width 0.1)
				(type default)
			)
			(layer "F.Fab")
		)
		(fp_line
			(start 0.12065 -0.3048)
			(end 0.67945 -0.3048)
			(stroke
				(width 0.1)
				(type default)
			)
			(layer "F.Fab")
		)
		(fp_line
			(start 0.12065 -0.2794)
			(end 0.12065 -0.3048)
			(stroke
				(width 0.1)
				(type default)
			)
			(layer "F.Fab")
		)
		(fp_line
			(start 0.67945 -0.3048)
			(end 0.67945 0.3048)
			(stroke
				(width 0.1)
				(type default)
			)
			(layer "F.Fab")
		)
		(fp_line
			(start 0.67945 0.3048)
			(end 0.120396 0.3048)
			(stroke
				(width 0.1)
				(type default)
			)
			(layer "F.Fab")
		)
		(pad "1" smd rect
			(at -0.40005 0 180)
			(size 0.4572 0.508)
			(layers "F.Cu" "F.Mask" "F.Paste")
			(net "P12V_LED_FAN1")
		)
		(pad "2" smd rect
			(at 0.40005 0 180)
			(size 0.4572 0.508)
			(layers "F.Cu" "F.Mask" "F.Paste")
			(net "FAN_1_OK_LED_R_N")
		)
	)
	(footprint ""
		(layer "F.Cu")
		(at 3.81 -127.508)
		(property "Reference" "R5567"
			(at 0 0 0)
			(layer "F.SilkS")
			(hide yes)
			(effects
				(font
					(size 1.27 1.27)
				)
			)
		)
		(property "Value" ""
			(at 0 0 0)
			(layer "F.Fab")
			(effects
				(font
					(size 1.27 1.27)
				)
			)
		)
		(duplicate_pad_numbers_are_jumpers no)
		(fp_line
			(start -0.7874 -0.4064)
			(end 0.7874 -0.4064)
			(stroke
				(width 0.1524)
				(type default)
			)
			(layer "F.SilkS")
		)
		(fp_line
			(start -0.7874 0.4064)
			(end -0.7874 -0.4064)
			(stroke
				(width 0.1524)
				(type default)
			)
			(layer "F.SilkS")
		)
		(fp_line
			(start 0.7874 -0.4064)
			(end 0.7874 0.4064)
			(stroke
				(width 0.1524)
				(type default)
			)
			(layer "F.SilkS")
		)
		(fp_line
			(start 0.7874 0.4064)
			(end -0.7874 0.4064)
			(stroke
				(width 0.1524)
				(type default)
			)
			(layer "F.SilkS")
		)
		(fp_line
			(start -0.67945 -0.305054)
			(end -0.12065 -0.305054)
			(stroke
				(width 0.1)
				(type default)
			)
			(layer "F.Fab")
		)
		(fp_line
			(start -0.67945 0.3048)
			(end -0.67945 -0.305054)
			(stroke
				(width 0.1)
				(type default)
			)
			(layer "F.Fab")
		)
		(fp_line
			(start -0.12065 -0.305054)
			(end -0.12065 -0.2794)
			(stroke
				(width 0.1)
				(type default)
			)
			(layer "F.Fab")
		)
		(fp_line
			(start -0.12065 -0.2794)
			(end 0.12065 -0.2794)
			(stroke
				(width 0.1)
				(type default)
			)
			(layer "F.Fab")
		)
		(fp_line
			(start -0.12065 0.2794)
			(end -0.12065 0.3048)
			(stroke
				(width 0.1)
				(type default)
			)
			(layer "F.Fab")
		)
		(fp_line
			(start -0.12065 0.3048)
			(end -0.67945 0.3048)
			(stroke
				(width 0.1)
				(type default)
			)
			(layer "F.Fab")
		)
		(fp_line
			(start 0.120396 0.2794)
			(end -0.12065 0.2794)
			(stroke
				(width 0.1)
				(type default)
			)
			(layer "F.Fab")
		)
		(fp_line
			(start 0.120396 0.3048)
			(end 0.120396 0.2794)
			(stroke
				(width 0.1)
				(type default)
			)
			(layer "F.Fab")
		)
		(fp_line
			(start 0.12065 -0.3048)
			(end 0.67945 -0.3048)
			(stroke
				(width 0.1)
				(type default)
			)
			(layer "F.Fab")
		)
		(fp_line
			(start 0.12065 -0.2794)
			(end 0.12065 -0.3048)
			(stroke
				(width 0.1)
				(type default)
			)
			(layer "F.Fab")
		)
		(fp_line
			(start 0.67945 -0.3048)
			(end 0.67945 0.3048)
			(stroke
				(width 0.1)
				(type default)
			)
			(layer "F.Fab")
		)
		(fp_line
			(start 0.67945 0.3048)
			(end 0.120396 0.3048)
			(stroke
				(width 0.1)
				(type default)
			)
			(layer "F.Fab")
		)
		(pad "1" smd circle
			(at -0.40005 0)
			(size 0 0)
			(layers "F.Cu" "F.Mask" "F.Paste")
			(net "P3V3_AUX")
		)
		(pad "2" smd circle
			(at 0.40005 0)
			(size 0 0)
			(layers "F.Cu" "F.Mask" "F.Paste")
			(net "U404_ADD2")
		)
	)
	(footprint ""
		(layer "F.Cu")
		(at 40.127428 -253.656846)
		(property "Reference" "R5419"
			(at 0 0 0)
			(layer "F.SilkS")
			(hide yes)
			(effects
				(font
					(size 1.27 1.27)
				)
			)
		)
		(property "Value" ""
			(at 0 0 0)
			(layer "F.Fab")
			(effects
				(font
					(size 1.27 1.27)
				)
			)
		)
		(duplicate_pad_numbers_are_jumpers no)
		(fp_line
			(start -0.7874 -0.4064)
			(end 0.7874 -0.4064)
			(stroke
				(width 0.1524)
				(type default)
			)
			(layer "F.SilkS")
		)
		(fp_line
			(start -0.7874 0.4064)
			(end -0.7874 -0.4064)
			(stroke
				(width 0.1524)
				(type default)
			)
			(layer "F.SilkS")
		)
		(fp_line
			(start 0.7874 -0.4064)
			(end 0.7874 0.4064)
			(stroke
				(width 0.1524)
				(type default)
			)
			(layer "F.SilkS")
		)
		(fp_line
			(start 0.7874 0.4064)
			(end -0.7874 0.4064)
			(stroke
				(width 0.1524)
				(type default)
			)
			(layer "F.SilkS")
		)
		(fp_line
			(start -0.67945 -0.305054)
			(end -0.12065 -0.305054)
			(stroke
				(width 0.1)
				(type default)
			)
			(layer "F.Fab")
		)
		(fp_line
			(start -0.67945 0.3048)
			(end -0.67945 -0.305054)
			(stroke
				(width 0.1)
				(type default)
			)
			(layer "F.Fab")
		)
		(fp_line
			(start -0.12065 -0.305054)
			(end -0.12065 -0.2794)
			(stroke
				(width 0.1)
				(type default)
			)
			(layer "F.Fab")
		)
		(fp_line
			(start -0.12065 -0.2794)
			(end 0.12065 -0.2794)
			(stroke
				(width 0.1)
				(type default)
			)
			(layer "F.Fab")
		)
		(fp_line
			(start -0.12065 0.2794)
			(end -0.12065 0.3048)
			(stroke
				(width 0.1)
				(type default)
			)
			(layer "F.Fab")
		)
		(fp_line
			(start -0.12065 0.3048)
			(end -0.67945 0.3048)
			(stroke
				(width 0.1)
				(type default)
			)
			(layer "F.Fab")
		)
		(fp_line
			(start 0.120396 0.2794)
			(end -0.12065 0.2794)
			(stroke
				(width 0.1)
				(type default)
			)
			(layer "F.Fab")
		)
		(fp_line
			(start 0.120396 0.3048)
			(end 0.120396 0.2794)
			(stroke
				(width 0.1)
				(type default)
			)
			(layer "F.Fab")
		)
		(fp_line
			(start 0.12065 -0.3048)
			(end 0.67945 -0.3048)
			(stroke
				(width 0.1)
				(type default)
			)
			(layer "F.Fab")
		)
		(fp_line
			(start 0.12065 -0.2794)
			(end 0.12065 -0.3048)
			(stroke
				(width 0.1)
				(type default)
			)
			(layer "F.Fab")
		)
		(fp_line
			(start 0.67945 -0.3048)
			(end 0.67945 0.3048)
			(stroke
				(width 0.1)
				(type default)
			)
			(layer "F.Fab")
		)
		(fp_line
			(start 0.67945 0.3048)
			(end 0.120396 0.3048)
			(stroke
				(width 0.1)
				(type default)
			)
			(layer "F.Fab")
		)
		(pad "1" smd circle
			(at -0.40005 0)
			(size 0 0)
			(layers "F.Cu" "F.Mask" "F.Paste")
			(net "FAN_1_ON")
		)
		(pad "2" smd circle
			(at 0.40005 0)
			(size 0 0)
			(layers "F.Cu" "F.Mask" "F.Paste")
			(net "P52V_FAN_1_EN")
		)
	)
	(footprint ""
		(layer "F.Cu")
		(at 38.6461 -133.858)
		(property "Reference" "R5576"
			(at 0 0 0)
			(layer "F.SilkS")
			(hide yes)
			(effects
				(font
					(size 1.27 1.27)
				)
			)
		)
		(property "Value" ""
			(at 0 0 0)
			(layer "F.Fab")
			(effects
				(font
					(size 1.27 1.27)
				)
			)
		)
		(duplicate_pad_numbers_are_jumpers no)
		(fp_line
			(start -0.7874 -0.4064)
			(end 0.7874 -0.4064)
			(stroke
				(width 0.1524)
				(type default)
			)
			(layer "F.SilkS")
		)
		(fp_line
			(start -0.7874 0.4064)
			(end -0.7874 -0.4064)
			(stroke
				(width 0.1524)
				(type default)
			)
			(layer "F.SilkS")
		)
		(fp_line
			(start 0.7874 -0.4064)
			(end 0.7874 0.4064)
			(stroke
				(width 0.1524)
				(type default)
			)
			(layer "F.SilkS")
		)
		(fp_line
			(start 0.7874 0.4064)
			(end -0.7874 0.4064)
			(stroke
				(width 0.1524)
				(type default)
			)
			(layer "F.SilkS")
		)
		(fp_line
			(start -0.67945 -0.305054)
			(end -0.12065 -0.305054)
			(stroke
				(width 0.1)
				(type default)
			)
			(layer "F.Fab")
		)
		(fp_line
			(start -0.67945 0.3048)
			(end -0.67945 -0.305054)
			(stroke
				(width 0.1)
				(type default)
			)
			(layer "F.Fab")
		)
		(fp_line
			(start -0.12065 -0.305054)
			(end -0.12065 -0.2794)
			(stroke
				(width 0.1)
				(type default)
			)
			(layer "F.Fab")
		)
		(fp_line
			(start -0.12065 -0.2794)
			(end 0.12065 -0.2794)
			(stroke
				(width 0.1)
				(type default)
			)
			(layer "F.Fab")
		)
		(fp_line
			(start -0.12065 0.2794)
			(end -0.12065 0.3048)
			(stroke
				(width 0.1)
				(type default)
			)
			(layer "F.Fab")
		)
		(fp_line
			(start -0.12065 0.3048)
			(end -0.67945 0.3048)
			(stroke
				(width 0.1)
				(type default)
			)
			(layer "F.Fab")
		)
		(fp_line
			(start 0.120396 0.2794)
			(end -0.12065 0.2794)
			(stroke
				(width 0.1)
				(type default)
			)
			(layer "F.Fab")
		)
		(fp_line
			(start 0.120396 0.3048)
			(end 0.120396 0.2794)
			(stroke
				(width 0.1)
				(type default)
			)
			(layer "F.Fab")
		)
		(fp_line
			(start 0.12065 -0.3048)
			(end 0.67945 -0.3048)
			(stroke
				(width 0.1)
				(type default)
			)
			(layer "F.Fab")
		)
		(fp_line
			(start 0.12065 -0.2794)
			(end 0.12065 -0.3048)
			(stroke
				(width 0.1)
				(type default)
			)
			(layer "F.Fab")
		)
		(fp_line
			(start 0.67945 -0.3048)
			(end 0.67945 0.3048)
			(stroke
				(width 0.1)
				(type default)
			)
			(layer "F.Fab")
		)
		(fp_line
			(start 0.67945 0.3048)
			(end 0.120396 0.3048)
			(stroke
				(width 0.1)
				(type default)
			)
			(layer "F.Fab")
		)
		(pad "1" smd rect
			(at -0.40005 0 180)
			(size 0.4572 0.508)
			(layers "F.Cu" "F.Mask" "F.Paste")
			(net "FAN_0_TACH_OL")
		)
		(pad "2" smd rect
			(at 0.40005 0 180)
			(size 0.4572 0.508)
			(layers "F.Cu" "F.Mask" "F.Paste")
			(net "FAN_0_TACH_OL_R2")
		)
	)
	(footprint ""
		(layer "F.Cu")
		(at 19.431 -298.45 -90)
		(property "Reference" "R5378"
			(at 0 0 270)
			(layer "F.SilkS")
			(hide yes)
			(effects
				(font
					(size 1.27 1.27)
				)
			)
		)
		(property "Value" ""
			(at 0 0 270)
			(layer "F.Fab")
			(effects
				(font
					(size 1.27 1.27)
				)
			)
		)
		(duplicate_pad_numbers_are_jumpers no)
		(fp_line
			(start -0.7874 0.4064)
			(end -0.7874 -0.4064)
			(stroke
				(width 0.1524)
				(type default)
			)
			(layer "F.SilkS")
		)
		(fp_line
			(start 0.7874 0.4064)
			(end -0.7874 0.4064)
			(stroke
				(width 0.1524)
				(type default)
			)
			(layer "F.SilkS")
		)
		(fp_line
			(start -0.7874 -0.4064)
			(end 0.7874 -0.4064)
			(stroke
				(width 0.1524)
				(type default)
			)
			(layer "F.SilkS")
		)
		(fp_line
			(start 0.7874 -0.4064)
			(end 0.7874 0.4064)
			(stroke
				(width 0.1524)
				(type default)
			)
			(layer "F.SilkS")
		)
		(fp_line
			(start -0.67945 0.3048)
			(end -0.67945 -0.305054)
			(stroke
				(width 0.1)
				(type default)
			)
			(layer "F.Fab")
		)
		(fp_line
			(start -0.12065 0.3048)
			(end -0.67945 0.3048)
			(stroke
				(width 0.1)
				(type default)
			)
			(layer "F.Fab")
		)
		(fp_line
			(start 0.120396 0.3048)
			(end 0.120396 0.2794)
			(stroke
				(width 0.1)
				(type default)
			)
			(layer "F.Fab")
		)
		(fp_line
			(start 0.67945 0.3048)
			(end 0.120396 0.3048)
			(stroke
				(width 0.1)
				(type default)
			)
			(layer "F.Fab")
		)
		(fp_line
			(start -0.12065 0.2794)
			(end -0.12065 0.3048)
			(stroke
				(width 0.1)
				(type default)
			)
			(layer "F.Fab")
		)
		(fp_line
			(start 0.120396 0.2794)
			(end -0.12065 0.2794)
			(stroke
				(width 0.1)
				(type default)
			)
			(layer "F.Fab")
		)
		(fp_line
			(start -0.12065 -0.2794)
			(end 0.12065 -0.2794)
			(stroke
				(width 0.1)
				(type default)
			)
			(layer "F.Fab")
		)
		(fp_line
			(start 0.12065 -0.2794)
			(end 0.12065 -0.3048)
			(stroke
				(width 0.1)
				(type default)
			)
			(layer "F.Fab")
		)
		(fp_line
			(start 0.12065 -0.3048)
			(end 0.67945 -0.3048)
			(stroke
				(width 0.1)
				(type default)
			)
			(layer "F.Fab")
		)
		(fp_line
			(start 0.67945 -0.3048)
			(end 0.67945 0.3048)
			(stroke
				(width 0.1)
				(type default)
			)
			(layer "F.Fab")
		)
		(fp_line
			(start -0.67945 -0.305054)
			(end -0.12065 -0.305054)
			(stroke
				(width 0.1)
				(type default)
			)
			(layer "F.Fab")
		)
		(fp_line
			(start -0.12065 -0.305054)
			(end -0.12065 -0.2794)
			(stroke
				(width 0.1)
				(type default)
			)
			(layer "F.Fab")
		)
		(pad "1" smd circle
			(at -0.40005 0 270)
			(size 0 0)
			(layers "F.Cu" "F.Mask" "F.Paste")
			(net "P3V3_AUX")
		)
		(pad "2" smd circle
			(at 0.40005 0 270)
			(size 0 0)
			(layers "F.Cu" "F.Mask" "F.Paste")
			(net "FAN_7_OK_R_LED")
		)
	)
)
